(kicad_pcb
	(version 20260206)
	(generator "pcbnew")
	(generator_version "10.0")
	(general
		(thickness 1.6)
		(legacy_teardrops no)
	)
	(paper "A4")
	(title_block
		(title "04192023_DAF0TMB3IC0_F0TG_MB_C_brd_V02_OCP.brd")
		(comment 1 "Grand Teton / footprints 5844-5850 of 8354")
	)
	(layers
		(0 "F.Cu" signal "TOP")
		(4 "In1.Cu" signal "GND")
		(6 "In2.Cu" signal "IN1")
		(8 "In3.Cu" signal "GND1")
		(10 "In4.Cu" signal "IN2")
		(12 "In5.Cu" signal "GND2")
		(14 "In6.Cu" signal "IN3")
		(16 "In7.Cu" signal "GND3")
		(18 "In8.Cu" signal "VCC")
		(20 "In9.Cu" signal "VCC1")
		(22 "In10.Cu" signal "GND4")
		(24 "In11.Cu" signal "IN4")
		(26 "In12.Cu" signal "GND5")
		(28 "In13.Cu" signal "IN5")
		(30 "In14.Cu" signal "GND6")
		(32 "In15.Cu" signal "IN6")
		(34 "In16.Cu" signal "GND7")
		(2 "B.Cu" signal "BOTTOM")
		(9 "F.Adhes" user "F.Adhesive")
		(11 "B.Adhes" user "B.Adhesive")
		(13 "F.Paste" user "Package Geometry/Pastemask Top")
		(15 "B.Paste" user "Package Geometry/Pastemask Bottom")
		(5 "F.SilkS" user "Ref Des/Silkscreen Top")
		(7 "B.SilkS" user "Ref Des/Silkscreen Bottom")
		(1 "F.Mask" user "Board Geometry/Soldermask Top")
		(3 "B.Mask" user "Board Geometry/Soldermask Bottom")
		(17 "Dwgs.User" user "User.Drawings")
		(19 "Cmts.User" user "User.Comments")
		(21 "Eco1.User" user "User.Eco1")
		(23 "Eco2.User" user "User.Eco2")
		(25 "Edge.Cuts" user "Board Geometry/Outline")
		(27 "Margin" user)
		(31 "F.CrtYd" user "Package Geometry/Place Bound Top")
		(29 "B.CrtYd" user "Package Geometry/Place Bound Bottom")
		(35 "F.Fab" user "Ref Des/Assembly Top")
		(33 "B.Fab" user "Ref Des/Assembly Bottom")
	)
	(footprint ""
		(layer "B.Cu")
		(at 429.40224 -108.867448 90)
		(property "Reference" "R3785"
			(at 0 0 90)
			(layer "B.SilkS")
			(hide yes)
			(effects
				(font
					(size 1.27 1.27)
				)
				(justify mirror)
			)
		)
		(property "Value" ""
			(at 0 0 90)
			(layer "B.Fab")
			(effects
				(font
					(size 1.27 1.27)
				)
				(justify mirror)
			)
		)
		(duplicate_pad_numbers_are_jumpers no)
		(fp_line
			(start 0.7874 -0.4064)
			(end -0.7874 -0.4064)
			(stroke
				(width 0.1524)
				(type default)
			)
			(layer "B.SilkS")
		)
		(fp_line
			(start -0.7874 -0.4064)
			(end -0.7874 0.4064)
			(stroke
				(width 0.1524)
				(type default)
			)
			(layer "B.SilkS")
		)
		(fp_line
			(start 0.7874 0.4064)
			(end 0.7874 -0.4064)
			(stroke
				(width 0.1524)
				(type default)
			)
			(layer "B.SilkS")
		)
		(fp_line
			(start -0.7874 0.4064)
			(end 0.7874 0.4064)
			(stroke
				(width 0.1524)
				(type default)
			)
			(layer "B.SilkS")
		)
		(fp_line
			(start 0.67945 -0.305054)
			(end 0.12065 -0.305054)
			(stroke
				(width 0.1)
				(type default)
			)
			(layer "B.Fab")
		)
		(fp_line
			(start 0.12065 -0.305054)
			(end 0.12065 -0.2794)
			(stroke
				(width 0.1)
				(type default)
			)
			(layer "B.Fab")
		)
		(fp_line
			(start -0.12065 -0.3048)
			(end -0.67945 -0.3048)
			(stroke
				(width 0.1)
				(type default)
			)
			(layer "B.Fab")
		)
		(fp_line
			(start -0.67945 -0.3048)
			(end -0.67945 0.3048)
			(stroke
				(width 0.1)
				(type default)
			)
			(layer "B.Fab")
		)
		(fp_line
			(start 0.12065 -0.2794)
			(end -0.12065 -0.2794)
			(stroke
				(width 0.1)
				(type default)
			)
			(layer "B.Fab")
		)
		(fp_line
			(start -0.12065 -0.2794)
			(end -0.12065 -0.3048)
			(stroke
				(width 0.1)
				(type default)
			)
			(layer "B.Fab")
		)
		(fp_line
			(start 0.12065 0.2794)
			(end 0.12065 0.3048)
			(stroke
				(width 0.1)
				(type default)
			)
			(layer "B.Fab")
		)
		(fp_line
			(start -0.120396 0.2794)
			(end 0.12065 0.2794)
			(stroke
				(width 0.1)
				(type default)
			)
			(layer "B.Fab")
		)
		(fp_line
			(start 0.67945 0.3048)
			(end 0.67945 -0.305054)
			(stroke
				(width 0.1)
				(type default)
			)
			(layer "B.Fab")
		)
		(fp_line
			(start 0.12065 0.3048)
			(end 0.67945 0.3048)
			(stroke
				(width 0.1)
				(type default)
			)
			(layer "B.Fab")
		)
		(fp_line
			(start -0.120396 0.3048)
			(end -0.120396 0.2794)
			(stroke
				(width 0.1)
				(type default)
			)
			(layer "B.Fab")
		)
		(fp_line
			(start -0.67945 0.3048)
			(end -0.120396 0.3048)
			(stroke
				(width 0.1)
				(type default)
			)
			(layer "B.Fab")
		)
		(pad "1" smd circle
			(at 0.40005 0 270)
			(size 0 0)
			(layers "B.Cu" "B.Mask" "B.Paste")
			(net "P3V3_OCP_UV_1_R1")
		)
		(pad "2" smd circle
			(at -0.40005 0 270)
			(size 0 0)
			(layers "B.Cu" "B.Mask" "B.Paste")
			(net "P3V3_OCP_UV_1")
		)
	)
	(footprint ""
		(layer "B.Cu")
		(at 36.040568 -195.8848 180)
		(property "Reference" "R1699"
			(at 0 0 0)
			(layer "B.SilkS")
			(hide yes)
			(effects
				(font
					(size 1.27 1.27)
				)
				(justify mirror)
			)
		)
		(property "Value" ""
			(at 0 0 0)
			(layer "B.Fab")
			(effects
				(font
					(size 1.27 1.27)
				)
				(justify mirror)
			)
		)
		(duplicate_pad_numbers_are_jumpers no)
		(fp_line
			(start 0.7874 0.4064)
			(end 0.7874 -0.4064)
			(stroke
				(width 0.1524)
				(type default)
			)
			(layer "B.SilkS")
		)
		(fp_line
			(start 0.7874 -0.4064)
			(end -0.7874 -0.4064)
			(stroke
				(width 0.1524)
				(type default)
			)
			(layer "B.SilkS")
		)
		(fp_line
			(start -0.7874 0.4064)
			(end 0.7874 0.4064)
			(stroke
				(width 0.1524)
				(type default)
			)
			(layer "B.SilkS")
		)
		(fp_line
			(start -0.7874 -0.4064)
			(end -0.7874 0.4064)
			(stroke
				(width 0.1524)
				(type default)
			)
			(layer "B.SilkS")
		)
		(fp_line
			(start 0.67945 0.3048)
			(end 0.67945 -0.305054)
			(stroke
				(width 0.1)
				(type default)
			)
			(layer "B.Fab")
		)
		(fp_line
			(start 0.67945 -0.305054)
			(end 0.12065 -0.305054)
			(stroke
				(width 0.1)
				(type default)
			)
			(layer "B.Fab")
		)
		(fp_line
			(start 0.12065 0.3048)
			(end 0.67945 0.3048)
			(stroke
				(width 0.1)
				(type default)
			)
			(layer "B.Fab")
		)
		(fp_line
			(start 0.12065 0.2794)
			(end 0.12065 0.3048)
			(stroke
				(width 0.1)
				(type default)
			)
			(layer "B.Fab")
		)
		(fp_line
			(start 0.12065 -0.2794)
			(end -0.12065 -0.2794)
			(stroke
				(width 0.1)
				(type default)
			)
			(layer "B.Fab")
		)
		(fp_line
			(start 0.12065 -0.305054)
			(end 0.12065 -0.2794)
			(stroke
				(width 0.1)
				(type default)
			)
			(layer "B.Fab")
		)
		(fp_line
			(start -0.120396 0.3048)
			(end -0.120396 0.2794)
			(stroke
				(width 0.1)
				(type default)
			)
			(layer "B.Fab")
		)
		(fp_line
			(start -0.120396 0.2794)
			(end 0.12065 0.2794)
			(stroke
				(width 0.1)
				(type default)
			)
			(layer "B.Fab")
		)
		(fp_line
			(start -0.12065 -0.2794)
			(end -0.12065 -0.3048)
			(stroke
				(width 0.1)
				(type default)
			)
			(layer "B.Fab")
		)
		(fp_line
			(start -0.12065 -0.3048)
			(end -0.67945 -0.3048)
			(stroke
				(width 0.1)
				(type default)
			)
			(layer "B.Fab")
		)
		(fp_line
			(start -0.67945 0.3048)
			(end -0.120396 0.3048)
			(stroke
				(width 0.1)
				(type default)
			)
			(layer "B.Fab")
		)
		(fp_line
			(start -0.67945 -0.3048)
			(end -0.67945 0.3048)
			(stroke
				(width 0.1)
				(type default)
			)
			(layer "B.Fab")
		)
		(pad "1" smd circle
			(at 0.40005 0)
			(size 0 0)
			(layers "B.Cu" "B.Mask" "B.Paste")
			(net "I3C_SPD_DDRAF_CPU1_SDA")
		)
		(pad "2" smd circle
			(at -0.40005 0)
			(size 0 0)
			(layers "B.Cu" "B.Mask" "B.Paste")
			(net "I3C_SPD_DDRD_CPU1_SDA")
		)
	)
	(footprint ""
		(layer "B.Cu")
		(at 170.39082 -425.053506 -90)
		(property "Reference" "R1198"
			(at 0 0 90)
			(layer "B.SilkS")
			(hide yes)
			(effects
				(font
					(size 1.27 1.27)
				)
				(justify mirror)
			)
		)
		(property "Value" ""
			(at 0 0 90)
			(layer "B.Fab")
			(effects
				(font
					(size 1.27 1.27)
				)
				(justify mirror)
			)
		)
		(duplicate_pad_numbers_are_jumpers no)
		(fp_line
			(start -0.32512 0.175006)
			(end 0.32512 0.175006)
			(stroke
				(width 0.1)
				(type default)
			)
			(layer "B.Fab")
		)
		(fp_line
			(start 0.32512 0.175006)
			(end 0.32512 -0.175006)
			(stroke
				(width 0.1)
				(type default)
			)
			(layer "B.Fab")
		)
		(fp_line
			(start -0.32512 -0.175006)
			(end -0.32512 0.175006)
			(stroke
				(width 0.1)
				(type default)
			)
			(layer "B.Fab")
		)
		(fp_line
			(start 0.32512 -0.175006)
			(end -0.32512 -0.175006)
			(stroke
				(width 0.1)
				(type default)
			)
			(layer "B.Fab")
		)
		(pad "1" smd rect
			(at 0.2667 0 90)
			(size 0.3048 0.381)
			(layers "B.Cu" "B.Mask" "B.Paste")
			(net "RST_SMB_RT_ROM_R1_N")
		)
		(pad "2" smd rect
			(at -0.2667 0 270)
			(size 0.3048 0.381)
			(layers "B.Cu" "B.Mask" "B.Paste")
			(net "FM_SMB_RT_ROM_MUX3_SEL")
		)
	)
	(footprint ""
		(layer "B.Cu")
		(at 398.04721 -398.969484)
		(property "Reference" "C966"
			(at 0 0 0)
			(layer "B.SilkS")
			(hide yes)
			(effects
				(font
					(size 1.27 1.27)
				)
				(justify mirror)
			)
		)
		(property "Value" ""
			(at 0 0 0)
			(layer "B.Fab")
			(effects
				(font
					(size 1.27 1.27)
				)
				(justify mirror)
			)
		)
		(duplicate_pad_numbers_are_jumpers no)
		(fp_line
			(start -1.524 -0.762)
			(end -1.524 0.762)
			(stroke
				(width 0.1524)
				(type default)
			)
			(layer "B.SilkS")
		)
		(fp_line
			(start -1.524 0.762)
			(end 1.524 0.762)
			(stroke
				(width 0.1524)
				(type default)
			)
			(layer "B.SilkS")
		)
		(fp_line
			(start 1.524 -0.762)
			(end -1.524 -0.762)
			(stroke
				(width 0.1524)
				(type default)
			)
			(layer "B.SilkS")
		)
		(fp_line
			(start 1.524 0.762)
			(end 1.524 -0.762)
			(stroke
				(width 0.1524)
				(type default)
			)
			(layer "B.SilkS")
		)
		(fp_line
			(start -1.1049 -0.724916)
			(end 1.1049 -0.724916)
			(stroke
				(width 0.1)
				(type default)
			)
			(layer "B.Fab")
		)
		(fp_line
			(start -1.1049 0.724916)
			(end -1.1049 -0.724916)
			(stroke
				(width 0.1)
				(type default)
			)
			(layer "B.Fab")
		)
		(fp_line
			(start 1.1049 -0.724916)
			(end 1.1049 0.724916)
			(stroke
				(width 0.1)
				(type default)
			)
			(layer "B.Fab")
		)
		(fp_line
			(start 1.1049 0.724916)
			(end -1.1049 0.724916)
			(stroke
				(width 0.1)
				(type default)
			)
			(layer "B.Fab")
		)
		(pad "1" smd rect
			(at 0.889 0)
			(size 1.016 1.27)
			(layers "B.Cu" "B.Mask" "B.Paste")
			(net "P0V9_CPU0_RT2_2A")
		)
		(pad "2" smd rect
			(at -0.889 0)
			(size 1.016 1.27)
			(layers "B.Cu" "B.Mask" "B.Paste")
			(net "GND")
		)
	)
	(footprint ""
		(layer "B.Cu")
		(at 311.733184 -338.082128 -90)
		(property "Reference" "PC130_3"
			(at 0 0 90)
			(layer "B.SilkS")
			(hide yes)
			(effects
				(font
					(size 1.27 1.27)
				)
				(justify mirror)
			)
		)
		(property "Value" ""
			(at 0 0 90)
			(layer "B.Fab")
			(effects
				(font
					(size 1.27 1.27)
				)
				(justify mirror)
			)
		)
		(duplicate_pad_numbers_are_jumpers no)
		(fp_line
			(start -1.524 0.762)
			(end 1.524 0.762)
			(stroke
				(width 0.1524)
				(type default)
			)
			(layer "B.SilkS")
		)
		(fp_line
			(start 1.524 0.762)
			(end 1.524 -0.762)
			(stroke
				(width 0.1524)
				(type default)
			)
			(layer "B.SilkS")
		)
		(fp_line
			(start -1.524 -0.762)
			(end -1.524 0.762)
			(stroke
				(width 0.1524)
				(type default)
			)
			(layer "B.SilkS")
		)
		(fp_line
			(start 1.524 -0.762)
			(end -1.524 -0.762)
			(stroke
				(width 0.1524)
				(type default)
			)
			(layer "B.SilkS")
		)
		(fp_line
			(start -1.1049 0.724916)
			(end -1.1049 -0.724916)
			(stroke
				(width 0.1)
				(type default)
			)
			(layer "B.Fab")
		)
		(fp_line
			(start 1.1049 0.724916)
			(end -1.1049 0.724916)
			(stroke
				(width 0.1)
				(type default)
			)
			(layer "B.Fab")
		)
		(fp_line
			(start -1.1049 -0.724916)
			(end 1.1049 -0.724916)
			(stroke
				(width 0.1)
				(type default)
			)
			(layer "B.Fab")
		)
		(fp_line
			(start 1.1049 -0.724916)
			(end 1.1049 0.724916)
			(stroke
				(width 0.1)
				(type default)
			)
			(layer "B.Fab")
		)
		(pad "1" smd rect
			(at 0.889 0 270)
			(size 1.016 1.27)
			(layers "B.Cu" "B.Mask" "B.Paste")
			(net "PVDDCR_CPU1_P0")
		)
		(pad "2" smd rect
			(at -0.889 0 270)
			(size 1.016 1.27)
			(layers "B.Cu" "B.Mask" "B.Paste")
			(net "GND")
		)
	)
	(footprint ""
		(layer "B.Cu")
		(at 176.264316 -32.137858 -90)
		(property "Reference" "PR4540"
			(at 0 0 90)
			(layer "B.SilkS")
			(hide yes)
			(effects
				(font
					(size 1.27 1.27)
				)
				(justify mirror)
			)
		)
		(property "Value" ""
			(at 0 0 90)
			(layer "B.Fab")
			(effects
				(font
					(size 1.27 1.27)
				)
				(justify mirror)
			)
		)
		(duplicate_pad_numbers_are_jumpers no)
		(fp_line
			(start -0.7874 0.4064)
			(end 0.7874 0.4064)
			(stroke
				(width 0.1524)
				(type default)
			)
			(layer "B.SilkS")
		)
		(fp_line
			(start 0.7874 0.4064)
			(end 0.7874 -0.4064)
			(stroke
				(width 0.1524)
				(type default)
			)
			(layer "B.SilkS")
		)
		(fp_line
			(start -0.7874 -0.4064)
			(end -0.7874 0.4064)
			(stroke
				(width 0.1524)
				(type default)
			)
			(layer "B.SilkS")
		)
		(fp_line
			(start 0.7874 -0.4064)
			(end -0.7874 -0.4064)
			(stroke
				(width 0.1524)
				(type default)
			)
			(layer "B.SilkS")
		)
		(fp_line
			(start -0.67945 0.3048)
			(end -0.120396 0.3048)
			(stroke
				(width 0.1)
				(type default)
			)
			(layer "B.Fab")
		)
		(fp_line
			(start -0.120396 0.3048)
			(end -0.120396 0.2794)
			(stroke
				(width 0.1)
				(type default)
			)
			(layer "B.Fab")
		)
		(fp_line
			(start 0.12065 0.3048)
			(end 0.67945 0.3048)
			(stroke
				(width 0.1)
				(type default)
			)
			(layer "B.Fab")
		)
		(fp_line
			(start 0.67945 0.3048)
			(end 0.67945 -0.305054)
			(stroke
				(width 0.1)
				(type default)
			)
			(layer "B.Fab")
		)
		(fp_line
			(start -0.120396 0.2794)
			(end 0.12065 0.2794)
			(stroke
				(width 0.1)
				(type default)
			)
			(layer "B.Fab")
		)
		(fp_line
			(start 0.12065 0.2794)
			(end 0.12065 0.3048)
			(stroke
				(width 0.1)
				(type default)
			)
			(layer "B.Fab")
		)
		(fp_line
			(start -0.12065 -0.2794)
			(end -0.12065 -0.3048)
			(stroke
				(width 0.1)
				(type default)
			)
			(layer "B.Fab")
		)
		(fp_line
			(start 0.12065 -0.2794)
			(end -0.12065 -0.2794)
			(stroke
				(width 0.1)
				(type default)
			)
			(layer "B.Fab")
		)
		(fp_line
			(start -0.67945 -0.3048)
			(end -0.67945 0.3048)
			(stroke
				(width 0.1)
				(type default)
			)
			(layer "B.Fab")
		)
		(fp_line
			(start -0.12065 -0.3048)
			(end -0.67945 -0.3048)
			(stroke
				(width 0.1)
				(type default)
			)
			(layer "B.Fab")
		)
		(fp_line
			(start 0.12065 -0.305054)
			(end 0.12065 -0.2794)
			(stroke
				(width 0.1)
				(type default)
			)
			(layer "B.Fab")
		)
		(fp_line
			(start 0.67945 -0.305054)
			(end 0.12065 -0.305054)
			(stroke
				(width 0.1)
				(type default)
			)
			(layer "B.Fab")
		)
		(pad "1" smd circle
			(at 0.40005 0 90)
			(size 0 0)
			(layers "B.Cu" "B.Mask" "B.Paste")
			(net "P12V_SCM_ISET")
		)
		(pad "2" smd circle
			(at -0.40005 0 90)
			(size 0 0)
			(layers "B.Cu" "B.Mask" "B.Paste")
			(net "P12V_SCM_ISET_R")
		)
	)
	(footprint ""
		(layer "B.Cu")
		(at 119.293386 -251.781564)
		(property "Reference" "C2259"
			(at 0 0 0)
			(layer "B.SilkS")
			(hide yes)
			(effects
				(font
					(size 1.27 1.27)
				)
				(justify mirror)
			)
		)
		(property "Value" ""
			(at 0 0 0)
			(layer "B.Fab")
			(effects
				(font
					(size 1.27 1.27)
				)
				(justify mirror)
			)
		)
		(duplicate_pad_numbers_are_jumpers no)
		(fp_line
			(start -0.7874 -0.4064)
			(end -0.7874 0.4064)
			(stroke
				(width 0.1524)
				(type default)
			)
			(layer "B.SilkS")
		)
		(fp_line
			(start -0.7874 0.4064)
			(end 0.7874 0.4064)
			(stroke
				(width 0.1524)
				(type default)
			)
			(layer "B.SilkS")
		)
		(fp_line
			(start 0.7874 -0.4064)
			(end -0.7874 -0.4064)
			(stroke
				(width 0.1524)
				(type default)
			)
			(layer "B.SilkS")
		)
		(fp_line
			(start 0.7874 0.4064)
			(end 0.7874 -0.4064)
			(stroke
				(width 0.1524)
				(type default)
			)
			(layer "B.SilkS")
		)
		(fp_line
			(start -0.67945 -0.3048)
			(end -0.67945 0.3048)
			(stroke
				(width 0.1)
				(type default)
			)
			(layer "B.Fab")
		)
		(fp_line
			(start -0.67945 0.3048)
			(end -0.120396 0.3048)
			(stroke
				(width 0.1)
				(type default)
			)
			(layer "B.Fab")
		)
		(fp_line
			(start -0.12065 -0.3048)
			(end -0.67945 -0.3048)
			(stroke
				(width 0.1)
				(type default)
			)
			(layer "B.Fab")
		)
		(fp_line
			(start -0.12065 -0.2794)
			(end -0.12065 -0.3048)
			(stroke
				(width 0.1)
				(type default)
			)
			(layer "B.Fab")
		)
		(fp_line
			(start -0.120396 0.2794)
			(end 0.12065 0.2794)
			(stroke
				(width 0.1)
				(type default)
			)
			(layer "B.Fab")
		)
		(fp_line
			(start -0.120396 0.3048)
			(end -0.120396 0.2794)
			(stroke
				(width 0.1)
				(type default)
			)
			(layer "B.Fab")
		)
		(fp_line
			(start 0.12065 -0.305054)
			(end 0.12065 -0.2794)
			(stroke
				(width 0.1)
				(type default)
			)
			(layer "B.Fab")
		)
		(fp_line
			(start 0.12065 -0.2794)
			(end -0.12065 -0.2794)
			(stroke
				(width 0.1)
				(type default)
			)
			(layer "B.Fab")
		)
		(fp_line
			(start 0.12065 0.2794)
			(end 0.12065 0.3048)
			(stroke
				(width 0.1)
				(type default)
			)
			(layer "B.Fab")
		)
		(fp_line
			(start 0.12065 0.3048)
			(end 0.67945 0.3048)
			(stroke
				(width 0.1)
				(type default)
			)
			(layer "B.Fab")
		)
		(fp_line
			(start 0.67945 -0.305054)
			(end 0.12065 -0.305054)
			(stroke
				(width 0.1)
				(type default)
			)
			(layer "B.Fab")
		)
		(fp_line
			(start 0.67945 0.3048)
			(end 0.67945 -0.305054)
			(stroke
				(width 0.1)
				(type default)
			)
			(layer "B.Fab")
		)
		(pad "1" smd circle
			(at 0.40005 0 180)
			(size 0 0)
			(layers "B.Cu" "B.Mask" "B.Paste")
			(net "PVDDCR_SOC_P1")
		)
		(pad "2" smd circle
			(at -0.40005 0 180)
			(size 0 0)
			(layers "B.Cu" "B.Mask" "B.Paste")
			(net "GND")
		)
	)
)
